# S9S_MB_2U (Grand Teton) — schematic netlist excerpt (pin names and nets, part order shuffled) for the footprints in the layout excerpt that follows; sources: Cadence DE-HDL packaged netlist, KiCad conversion of 03242023_DA0F0TMBIJ0_F0T_Motherboard_J_brd_V01_OCP.brd

PR300  Q_RES  2.2 1% CHIP  pkg 0402LF  page 286 : A = PVCCIN_CPU1_PVCC ; B = PVCCIN_CPU1_VDD3
R4512  Q_RES  33.2 1% CHIP  pkg 0402LF  page 241 : A = SMB_HOST_3V3AUX_SCL ; B = SMB_HOST_3V3AUX_SCL_R5

(kicad_pcb
	(version 20260206)
	(generator "pcbnew")
	(generator_version "10.0")
	(general
		(thickness 1.6)
		(legacy_teardrops no)
	)
	(paper "A4")
	(title_block
		(title "03242023_DA0F0TMBIJ0_F0T_Motherboard_J_brd_V01_OCP.brd")
		(comment 1 "Grand Teton / footprints 4157-4158 of 6105")
	)
	(layers
		(0 "F.Cu" signal "TOP")
		(4 "In1.Cu" signal "GND")
		(6 "In2.Cu" signal "IN1")
		(8 "In3.Cu" signal "GND1")
		(10 "In4.Cu" signal "IN2")
		(12 "In5.Cu" signal "GND2")
		(14 "In6.Cu" signal "IN3")
		(16 "In7.Cu" signal "GND3")
		(18 "In8.Cu" signal "VCC")
		(20 "In9.Cu" signal "VCC1")
		(22 "In10.Cu" signal "GND4")
		(24 "In11.Cu" signal "IN4")
		(26 "In12.Cu" signal "GND5")
		(28 "In13.Cu" signal "IN5")
		(30 "In14.Cu" signal "GND6")
		(32 "In15.Cu" signal "IN6")
		(34 "In16.Cu" signal "GND7")
		(2 "B.Cu" signal "BOTTOM")
		(9 "F.Adhes" user "F.Adhesive")
		(11 "B.Adhes" user "B.Adhesive")
		(13 "F.Paste" user "Package Geometry/Pastemask Top")
		(15 "B.Paste" user "Package Geometry/Pastemask Bottom")
		(5 "F.SilkS" user "Ref Des/Silkscreen Top")
		(7 "B.SilkS" user "Ref Des/Silkscreen Bottom")
		(1 "F.Mask" user "Board Geometry/Soldermask Top")
		(3 "B.Mask" user "Board Geometry/Soldermask Bottom")
		(17 "Dwgs.User" user "User.Drawings")
		(19 "Cmts.User" user "User.Comments")
		(21 "Eco1.User" user "User.Eco1")
		(23 "Eco2.User" user "User.Eco2")
		(25 "Edge.Cuts" user "Board Geometry/Outline")
		(27 "Margin" user)
		(31 "F.CrtYd" user "Package Geometry/Place Bound Top")
		(29 "B.CrtYd" user "Package Geometry/Place Bound Bottom")
		(35 "F.Fab" user "Ref Des/Assembly Top")
		(33 "B.Fab" user "Ref Des/Assembly Bottom")
	)
	(footprint ""
		(layer "B.Cu")
		(at 110.922054 -334.703166 -90)
		(property "Reference" "PR300"
			(at 0 0 90)
			(layer "B.SilkS")
			(hide yes)
			(effects
				(font
					(size 1.27 1.27)
				)
				(justify mirror)
			)
		)
		(property "Value" ""
			(at 0 0 90)
			(layer "B.Fab")
			(effects
				(font
					(size 1.27 1.27)
				)
				(justify mirror)
			)
		)
		(duplicate_pad_numbers_are_jumpers no)
		(fp_line
			(start -0.7874 0.4064)
			(end 0.7874 0.4064)
			(stroke
				(width 0.1524)
				(type default)
			)
			(layer "B.SilkS")
		)
		(fp_line
			(start 0.7874 0.4064)
			(end 0.7874 -0.4064)
			(stroke
				(width 0.1524)
				(type default)
			)
			(layer "B.SilkS")
		)
		(fp_line
			(start -0.7874 -0.4064)
			(end -0.7874 0.4064)
			(stroke
				(width 0.1524)
				(type default)
			)
			(layer "B.SilkS")
		)
		(fp_line
			(start 0.7874 -0.4064)
			(end -0.7874 -0.4064)
			(stroke
				(width 0.1524)
				(type default)
			)
			(layer "B.SilkS")
		)
		(fp_line
			(start -0.67945 0.3048)
			(end -0.120396 0.3048)
			(stroke
				(width 0.1)
				(type default)
			)
			(layer "B.Fab")
		)
		(fp_line
			(start -0.120396 0.3048)
			(end -0.120396 0.2794)
			(stroke
				(width 0.1)
				(type default)
			)
			(layer "B.Fab")
		)
		(fp_line
			(start 0.12065 0.3048)
			(end 0.67945 0.3048)
			(stroke
				(width 0.1)
				(type default)
			)
			(layer "B.Fab")
		)
		(fp_line
			(start 0.67945 0.3048)
			(end 0.67945 -0.305054)
			(stroke
				(width 0.1)
				(type default)
			)
			(layer "B.Fab")
		)
		(fp_line
			(start -0.120396 0.2794)
			(end 0.12065 0.2794)
			(stroke
				(width 0.1)
				(type default)
			)
			(layer "B.Fab")
		)
		(fp_line
			(start 0.12065 0.2794)
			(end 0.12065 0.3048)
			(stroke
				(width 0.1)
				(type default)
			)
			(layer "B.Fab")
		)
		(fp_line
			(start -0.12065 -0.2794)
			(end -0.12065 -0.3048)
			(stroke
				(width 0.1)
				(type default)
			)
			(layer "B.Fab")
		)
		(fp_line
			(start 0.12065 -0.2794)
			(end -0.12065 -0.2794)
			(stroke
				(width 0.1)
				(type default)
			)
			(layer "B.Fab")
		)
		(fp_line
			(start -0.67945 -0.3048)
			(end -0.67945 0.3048)
			(stroke
				(width 0.1)
				(type default)
			)
			(layer "B.Fab")
		)
		(fp_line
			(start -0.12065 -0.3048)
			(end -0.67945 -0.3048)
			(stroke
				(width 0.1)
				(type default)
			)
			(layer "B.Fab")
		)
		(fp_line
			(start 0.12065 -0.305054)
			(end 0.12065 -0.2794)
			(stroke
				(width 0.1)
				(type default)
			)
			(layer "B.Fab")
		)
		(fp_line
			(start 0.67945 -0.305054)
			(end 0.12065 -0.305054)
			(stroke
				(width 0.1)
				(type default)
			)
			(layer "B.Fab")
		)
		(pad "1" smd circle
			(at 0.40005 0 90)
			(size 0 0)
			(layers "B.Cu" "B.Mask" "B.Paste")
			(net "PVCCIN_CPU1_PVCC")
		)
		(pad "2" smd circle
			(at -0.40005 0 90)
			(size 0 0)
			(layers "B.Cu" "B.Mask" "B.Paste")
			(net "PVCCIN_CPU1_VDD3")
		)
	)
	(footprint ""
		(layer "B.Cu")
		(at 184.912 -20.284948 90)
		(property "Reference" "R4512"
			(at 0 0 90)
			(layer "B.SilkS")
			(hide yes)
			(effects
				(font
					(size 1.27 1.27)
				)
				(justify mirror)
			)
		)
		(property "Value" ""
			(at 0 0 90)
			(layer "B.Fab")
			(effects
				(font
					(size 1.27 1.27)
				)
				(justify mirror)
			)
		)
		(duplicate_pad_numbers_are_jumpers no)
		(fp_line
			(start 0.7874 -0.4064)
			(end -0.7874 -0.4064)
			(stroke
				(width 0.1524)
				(type default)
			)
			(layer "B.SilkS")
		)
		(fp_line
			(start -0.7874 -0.4064)
			(end -0.7874 0.4064)
			(stroke
				(width 0.1524)
				(type default)
			)
			(layer "B.SilkS")
		)
		(fp_line
			(start 0.7874 0.4064)
			(end 0.7874 -0.4064)
			(stroke
				(width 0.1524)
				(type default)
			)
			(layer "B.SilkS")
		)
		(fp_line
			(start -0.7874 0.4064)
			(end 0.7874 0.4064)
			(stroke
				(width 0.1524)
				(type default)
			)
			(layer "B.SilkS")
		)
		(fp_line
			(start 0.67945 -0.305054)
			(end 0.12065 -0.305054)
			(stroke
				(width 0.1)
				(type default)
			)
			(layer "B.Fab")
		)
		(fp_line
			(start 0.12065 -0.305054)
			(end 0.12065 -0.2794)
			(stroke
				(width 0.1)
				(type default)
			)
			(layer "B.Fab")
		)
		(fp_line
			(start -0.12065 -0.3048)
			(end -0.67945 -0.3048)
			(stroke
				(width 0.1)
				(type default)
			)
			(layer "B.Fab")
		)
		(fp_line
			(start -0.67945 -0.3048)
			(end -0.67945 0.3048)
			(stroke
				(width 0.1)
				(type default)
			)
			(layer "B.Fab")
		)
		(fp_line
			(start 0.12065 -0.2794)
			(end -0.12065 -0.2794)
			(stroke
				(width 0.1)
				(type default)
			)
			(layer "B.Fab")
		)
		(fp_line
			(start -0.12065 -0.2794)
			(end -0.12065 -0.3048)
			(stroke
				(width 0.1)
				(type default)
			)
			(layer "B.Fab")
		)
		(fp_line
			(start 0.12065 0.2794)
			(end 0.12065 0.3048)
			(stroke
				(width 0.1)
				(type default)
			)
			(layer "B.Fab")
		)
		(fp_line
			(start -0.120396 0.2794)
			(end 0.12065 0.2794)
			(stroke
				(width 0.1)
				(type default)
			)
			(layer "B.Fab")
		)
		(fp_line
			(start 0.67945 0.3048)
			(end 0.67945 -0.305054)
			(stroke
				(width 0.1)
				(type default)
			)
			(layer "B.Fab")
		)
		(fp_line
			(start 0.12065 0.3048)
			(end 0.67945 0.3048)
			(stroke
				(width 0.1)
				(type default)
			)
			(layer "B.Fab")
		)
		(fp_line
			(start -0.120396 0.3048)
			(end -0.120396 0.2794)
			(stroke
				(width 0.1)
				(type default)
			)
			(layer "B.Fab")
		)
		(fp_line
			(start -0.67945 0.3048)
			(end -0.120396 0.3048)
			(stroke
				(width 0.1)
				(type default)
			)
			(layer "B.Fab")
		)
		(pad "1" smd circle
			(at 0.40005 0 270)
			(size 0 0)
			(layers "B.Cu" "B.Mask" "B.Paste")
			(net "SMB_HOST_3V3AUX_SCL")
		)
		(pad "2" smd circle
			(at -0.40005 0 270)
			(size 0 0)
			(layers "B.Cu" "B.Mask" "B.Paste")
			(net "SMB_HOST_3V3AUX_SCL_R5")
		)
	)
)
